# T6G (Grand Teton) — schematic netlist excerpt (pin names and nets, part order shuffled) for the footprints in the layout excerpt that follows; sources: Cadence DE-HDL packaged netlist, KiCad conversion of 04192023_DAF0TMB3IC0_F0TG_MB_C_brd_V02_OCP.brd

R4123  Q_RES  54.9K 1% EMPTY  pkg 0402LF  page 125 : A = P3V3_AUX ; B = GPU_3V3IO_RSVD1_FFU
PR6807  Q_RES  0 5% EMPTY  pkg 0402LF  page 362 : A = P12V_AUX ; B = P0V9_RETIMER_CPU0_VMON
C778  Q_CAP  0.1UF 10V 10% X7S  pkg C0201  page 301 : A = P1V8_CPU0_RT2_1A ; B = GND

(kicad_pcb
	(version 20260206)
	(generator "pcbnew")
	(generator_version "10.0")
	(general
		(thickness 1.6)
		(legacy_teardrops no)
	)
	(paper "A4")
	(title_block
		(title "04192023_DAF0TMB3IC0_F0TG_MB_C_brd_V02_OCP.brd")
		(comment 1 "Grand Teton / footprints 7834-7836 of 8354")
	)
	(layers
		(0 "F.Cu" signal "TOP")
		(4 "In1.Cu" signal "GND")
		(6 "In2.Cu" signal "IN1")
		(8 "In3.Cu" signal "GND1")
		(10 "In4.Cu" signal "IN2")
		(12 "In5.Cu" signal "GND2")
		(14 "In6.Cu" signal "IN3")
		(16 "In7.Cu" signal "GND3")
		(18 "In8.Cu" signal "VCC")
		(20 "In9.Cu" signal "VCC1")
		(22 "In10.Cu" signal "GND4")
		(24 "In11.Cu" signal "IN4")
		(26 "In12.Cu" signal "GND5")
		(28 "In13.Cu" signal "IN5")
		(30 "In14.Cu" signal "GND6")
		(32 "In15.Cu" signal "IN6")
		(34 "In16.Cu" signal "GND7")
		(2 "B.Cu" signal "BOTTOM")
		(9 "F.Adhes" user "F.Adhesive")
		(11 "B.Adhes" user "B.Adhesive")
		(13 "F.Paste" user "Package Geometry/Pastemask Top")
		(15 "B.Paste" user "Package Geometry/Pastemask Bottom")
		(5 "F.SilkS" user "Ref Des/Silkscreen Top")
		(7 "B.SilkS" user "Ref Des/Silkscreen Bottom")
		(1 "F.Mask" user "Board Geometry/Soldermask Top")
		(3 "B.Mask" user "Board Geometry/Soldermask Bottom")
		(17 "Dwgs.User" user "User.Drawings")
		(19 "Cmts.User" user "User.Comments")
		(21 "Eco1.User" user "User.Eco1")
		(23 "Eco2.User" user "User.Eco2")
		(25 "Edge.Cuts" user "Board Geometry/Outline")
		(27 "Margin" user)
		(31 "F.CrtYd" user "Package Geometry/Place Bound Top")
		(29 "B.CrtYd" user "Package Geometry/Place Bound Bottom")
		(35 "F.Fab" user "Ref Des/Assembly Top")
		(33 "B.Fab" user "Ref Des/Assembly Bottom")
	)
	(footprint ""
		(layer "B.Cu")
		(at 164.403532 -430.59858 -90)
		(property "Reference" "R4123"
			(at 0 0 90)
			(layer "B.SilkS")
			(hide yes)
			(effects
				(font
					(size 1.27 1.27)
				)
				(justify mirror)
			)
		)
		(property "Value" ""
			(at 0 0 90)
			(layer "B.Fab")
			(effects
				(font
					(size 1.27 1.27)
				)
				(justify mirror)
			)
		)
		(duplicate_pad_numbers_are_jumpers no)
		(fp_line
			(start -0.7874 0.4064)
			(end 0.7874 0.4064)
			(stroke
				(width 0.1524)
				(type default)
			)
			(layer "B.SilkS")
		)
		(fp_line
			(start 0.7874 0.4064)
			(end 0.7874 -0.4064)
			(stroke
				(width 0.1524)
				(type default)
			)
			(layer "B.SilkS")
		)
		(fp_line
			(start -0.7874 -0.4064)
			(end -0.7874 0.4064)
			(stroke
				(width 0.1524)
				(type default)
			)
			(layer "B.SilkS")
		)
		(fp_line
			(start 0.7874 -0.4064)
			(end -0.7874 -0.4064)
			(stroke
				(width 0.1524)
				(type default)
			)
			(layer "B.SilkS")
		)
		(fp_line
			(start -0.67945 0.3048)
			(end -0.120396 0.3048)
			(stroke
				(width 0.1)
				(type default)
			)
			(layer "B.Fab")
		)
		(fp_line
			(start -0.120396 0.3048)
			(end -0.120396 0.2794)
			(stroke
				(width 0.1)
				(type default)
			)
			(layer "B.Fab")
		)
		(fp_line
			(start 0.12065 0.3048)
			(end 0.67945 0.3048)
			(stroke
				(width 0.1)
				(type default)
			)
			(layer "B.Fab")
		)
		(fp_line
			(start 0.67945 0.3048)
			(end 0.67945 -0.305054)
			(stroke
				(width 0.1)
				(type default)
			)
			(layer "B.Fab")
		)
		(fp_line
			(start -0.120396 0.2794)
			(end 0.12065 0.2794)
			(stroke
				(width 0.1)
				(type default)
			)
			(layer "B.Fab")
		)
		(fp_line
			(start 0.12065 0.2794)
			(end 0.12065 0.3048)
			(stroke
				(width 0.1)
				(type default)
			)
			(layer "B.Fab")
		)
		(fp_line
			(start -0.12065 -0.2794)
			(end -0.12065 -0.3048)
			(stroke
				(width 0.1)
				(type default)
			)
			(layer "B.Fab")
		)
		(fp_line
			(start 0.12065 -0.2794)
			(end -0.12065 -0.2794)
			(stroke
				(width 0.1)
				(type default)
			)
			(layer "B.Fab")
		)
		(fp_line
			(start -0.67945 -0.3048)
			(end -0.67945 0.3048)
			(stroke
				(width 0.1)
				(type default)
			)
			(layer "B.Fab")
		)
		(fp_line
			(start -0.12065 -0.3048)
			(end -0.67945 -0.3048)
			(stroke
				(width 0.1)
				(type default)
			)
			(layer "B.Fab")
		)
		(fp_line
			(start 0.12065 -0.305054)
			(end 0.12065 -0.2794)
			(stroke
				(width 0.1)
				(type default)
			)
			(layer "B.Fab")
		)
		(fp_line
			(start 0.67945 -0.305054)
			(end 0.12065 -0.305054)
			(stroke
				(width 0.1)
				(type default)
			)
			(layer "B.Fab")
		)
		(pad "1" smd circle
			(at 0.40005 0 90)
			(size 0 0)
			(layers "B.Cu" "B.Mask" "B.Paste")
			(net "P3V3_AUX")
		)
		(pad "2" smd circle
			(at -0.40005 0 90)
			(size 0 0)
			(layers "B.Cu" "B.Mask" "B.Paste")
			(net "GPU_3V3IO_RSVD1_FFU")
		)
	)
	(footprint ""
		(layer "B.Cu")
		(at 410.20619 -395.148562 90)
		(property "Reference" "C778"
			(at 0 0 90)
			(layer "B.SilkS")
			(hide yes)
			(effects
				(font
					(size 1.27 1.27)
				)
				(justify mirror)
			)
		)
		(property "Value" ""
			(at 0 0 90)
			(layer "B.Fab")
			(effects
				(font
					(size 1.27 1.27)
				)
				(justify mirror)
			)
		)
		(duplicate_pad_numbers_are_jumpers no)
		(fp_line
			(start 0.299974 -0.150114)
			(end -0.299974 -0.150114)
			(stroke
				(width 0.1)
				(type default)
			)
			(layer "B.Fab")
		)
		(fp_line
			(start -0.299974 -0.150114)
			(end -0.299974 0.150114)
			(stroke
				(width 0.1)
				(type default)
			)
			(layer "B.Fab")
		)
		(fp_line
			(start 0.299974 0.150114)
			(end 0.299974 -0.150114)
			(stroke
				(width 0.1)
				(type default)
			)
			(layer "B.Fab")
		)
		(fp_line
			(start -0.299974 0.150114)
			(end 0.299974 0.150114)
			(stroke
				(width 0.1)
				(type default)
			)
			(layer "B.Fab")
		)
		(pad "1" smd rect
			(at 0.2667 0 270)
			(size 0.3048 0.381)
			(layers "B.Cu" "B.Mask" "B.Paste")
			(net "P1V8_CPU0_RT2_1A")
		)
		(pad "2" smd rect
			(at -0.2667 0 270)
			(size 0.3048 0.381)
			(layers "B.Cu" "B.Mask" "B.Paste")
			(net "GND")
		)
	)
	(footprint ""
		(layer "B.Cu")
		(at 447.275966 -419.850824 -90)
		(property "Reference" "PR6807"
			(at 0 0 90)
			(layer "B.SilkS")
			(hide yes)
			(effects
				(font
					(size 1.27 1.27)
				)
				(justify mirror)
			)
		)
		(property "Value" ""
			(at 0 0 90)
			(layer "B.Fab")
			(effects
				(font
					(size 1.27 1.27)
				)
				(justify mirror)
			)
		)
		(duplicate_pad_numbers_are_jumpers no)
		(fp_line
			(start -0.7874 0.4064)
			(end 0.7874 0.4064)
			(stroke
				(width 0.1524)
				(type default)
			)
			(layer "B.SilkS")
		)
		(fp_line
			(start 0.7874 0.4064)
			(end 0.7874 -0.4064)
			(stroke
				(width 0.1524)
				(type default)
			)
			(layer "B.SilkS")
		)
		(fp_line
			(start -0.7874 -0.4064)
			(end -0.7874 0.4064)
			(stroke
				(width 0.1524)
				(type default)
			)
			(layer "B.SilkS")
		)
		(fp_line
			(start 0.7874 -0.4064)
			(end -0.7874 -0.4064)
			(stroke
				(width 0.1524)
				(type default)
			)
			(layer "B.SilkS")
		)
		(fp_line
			(start -0.67945 0.3048)
			(end -0.120396 0.3048)
			(stroke
				(width 0.1)
				(type default)
			)
			(layer "B.Fab")
		)
		(fp_line
			(start -0.120396 0.3048)
			(end -0.120396 0.2794)
			(stroke
				(width 0.1)
				(type default)
			)
			(layer "B.Fab")
		)
		(fp_line
			(start 0.12065 0.3048)
			(end 0.67945 0.3048)
			(stroke
				(width 0.1)
				(type default)
			)
			(layer "B.Fab")
		)
		(fp_line
			(start 0.67945 0.3048)
			(end 0.67945 -0.305054)
			(stroke
				(width 0.1)
				(type default)
			)
			(layer "B.Fab")
		)
		(fp_line
			(start -0.120396 0.2794)
			(end 0.12065 0.2794)
			(stroke
				(width 0.1)
				(type default)
			)
			(layer "B.Fab")
		)
		(fp_line
			(start 0.12065 0.2794)
			(end 0.12065 0.3048)
			(stroke
				(width 0.1)
				(type default)
			)
			(layer "B.Fab")
		)
		(fp_line
			(start -0.12065 -0.2794)
			(end -0.12065 -0.3048)
			(stroke
				(width 0.1)
				(type default)
			)
			(layer "B.Fab")
		)
		(fp_line
			(start 0.12065 -0.2794)
			(end -0.12065 -0.2794)
			(stroke
				(width 0.1)
				(type default)
			)
			(layer "B.Fab")
		)
		(fp_line
			(start -0.67945 -0.3048)
			(end -0.67945 0.3048)
			(stroke
				(width 0.1)
				(type default)
			)
			(layer "B.Fab")
		)
		(fp_line
			(start -0.12065 -0.3048)
			(end -0.67945 -0.3048)
			(stroke
				(width 0.1)
				(type default)
			)
			(layer "B.Fab")
		)
		(fp_line
			(start 0.12065 -0.305054)
			(end 0.12065 -0.2794)
			(stroke
				(width 0.1)
				(type default)
			)
			(layer "B.Fab")
		)
		(fp_line
			(start 0.67945 -0.305054)
			(end 0.12065 -0.305054)
			(stroke
				(width 0.1)
				(type default)
			)
			(layer "B.Fab")
		)
		(pad "1" smd circle
			(at 0.40005 0 90)
			(size 0 0)
			(layers "B.Cu" "B.Mask" "B.Paste")
			(net "P12V_AUX")
		)
		(pad "2" smd circle
			(at -0.40005 0 90)
			(size 0 0)
			(layers "B.Cu" "B.Mask" "B.Paste")
			(net "P0V9_RETIMER_CPU0_VMON")
		)
	)
)
